(kicad_pcb
	(version 20241229)
	(generator "pcbnew")
	(generator_version "9.0")
	(general
		(thickness 1.63)
		(legacy_teardrops no)
	)
	(paper "A4")
	(title_block
		(title "CM4 Baseboard")
		(date "2026-01-05")
		(rev "1.1.1")
		(company "Antmicro Ltd")
		(comment 1 "www.antmicro.com")
		(comment 9 "footprints 404-407 of 506")
	)
	(layers
		(0 "F.Cu" signal)
		(4 "In1.Cu" power)
		(6 "In2.Cu" power)
		(8 "In3.Cu" signal)
		(10 "In4.Cu" signal)
		(2 "B.Cu" signal)
		(9 "F.Adhes" user "F.Adhesive")
		(11 "B.Adhes" user "B.Adhesive")
		(13 "F.Paste" user)
		(15 "B.Paste" user)
		(5 "F.SilkS" user "F.Silkscreen")
		(7 "B.SilkS" user "B.Silkscreen")
		(1 "F.Mask" user)
		(3 "B.Mask" user)
		(17 "Dwgs.User" user "User.Drawings")
		(19 "Cmts.User" user "User.Comments")
		(21 "Eco1.User" user "User.Eco1")
		(23 "Eco2.User" user "User.Eco2")
		(25 "Edge.Cuts" user)
		(27 "Margin" user)
		(31 "F.CrtYd" user "F.Courtyard")
		(29 "B.CrtYd" user "B.Courtyard")
		(35 "F.Fab" user)
		(33 "B.Fab" user)
	)
	(footprint "antmicro-footprints:SOD-523"
		(layer "B.Cu")
		(at 113.592962 117.2665 180)
		(property "Reference" "D710"
			(at -2.245 -5.86 0)
			(layer "B.SilkS")
			(effects
				(font
					(size 0.7 0.7)
					(thickness 0.15)
				)
				(justify left bottom mirror)
			)
		)
		(property "Value" "RB521S30T1G"
			(at 0 -1.499 0)
			(layer "B.Fab")
			(effects
				(font
					(size 0.7 0.7)
					(thickness 0.15)
				)
				(justify left bottom mirror)
			)
		)
		(property "Datasheet" "https://www.onsemi.com/pdf/datasheet/rb521s30t1-d.pdf"
			(at 0 0 180)
			(layer "B.Fab")
			(hide yes)
			(effects
				(font
					(size 1.27 1.27)
					(thickness 0.15)
				)
			)
		)
		(property "MPN" "RB521S30T1G"
			(at 0 0 180)
			(unlocked yes)
			(layer "B.Fab")
			(hide yes)
			(effects
				(font
					(size 1 1)
					(thickness 0.15)
				)
				(justify mirror)
			)
		)
		(property "Manufacturer" "ON Semiconductor"
			(at 0 0 180)
			(unlocked yes)
			(layer "B.Fab")
			(hide yes)
			(effects
				(font
					(size 1 1)
					(thickness 0.15)
				)
				(justify mirror)
			)
		)
		(property "Author" "Antmicro"
			(at 0 0 180)
			(unlocked yes)
			(layer "B.Fab")
			(hide yes)
			(effects
				(font
					(size 1 1)
					(thickness 0.15)
				)
				(justify mirror)
			)
		)
		(property "License" "Apache-2.0"
			(at 0 0 180)
			(unlocked yes)
			(layer "B.Fab")
			(hide yes)
			(effects
				(font
					(size 1 1)
					(thickness 0.15)
				)
				(justify mirror)
			)
		)
		(sheetname "/Display/")
		(sheetfile "display.kicad_sch")
		(attr smd)
		(fp_line
			(start -0.35 0.5)
			(end -0.35 -0.5)
			(stroke
				(width 0.15)
				(type solid)
			)
			(layer "B.SilkS")
		)
		(fp_rect
			(start -1 0.6)
			(end 1 -0.6)
			(stroke
				(width 0.05)
				(type solid)
			)
			(fill no)
			(layer "B.CrtYd")
		)
		(fp_line
			(start 0.65 0.425)
			(end 0.65 -0.423)
			(stroke
				(width 0.15)
				(type solid)
			)
			(layer "B.Fab")
		)
		(fp_line
			(start -0.35 0.4)
			(end -0.35 -0.4)
			(stroke
				(width 0.15)
				(type solid)
			)
			(layer "B.Fab")
		)
		(fp_line
			(start -0.652 0.425)
			(end 0.65 0.425)
			(stroke
				(width 0.15)
				(type solid)
			)
			(layer "B.Fab")
		)
		(fp_line
			(start -0.652 -0.423)
			(end 0.65 -0.423)
			(stroke
				(width 0.15)
				(type solid)
			)
			(layer "B.Fab")
		)
		(fp_line
			(start -0.652 -0.423)
			(end -0.652 0.425)
			(stroke
				(width 0.15)
				(type solid)
			)
			(layer "B.Fab")
		)
		(fp_text user "Author: Antmicro"
			(at -1.276 -4.7 0)
			(layer "B.Fab")
			(effects
				(font
					(size 0.7 0.7)
					(thickness 0.15)
				)
				(justify left bottom mirror)
			)
		)
		(fp_text user "${REFERENCE}"
			(at -1.276 -3.499 0)
			(layer "B.Fab")
			(effects
				(font
					(size 0.7 0.7)
					(thickness 0.15)
				)
				(justify left bottom mirror)
			)
		)
		(fp_text user "License: Apache-2.0"
			(at -1.276 -5.9 0)
			(layer "B.Fab")
			(effects
				(font
					(size 0.7 0.7)
					(thickness 0.15)
				)
				(justify left bottom mirror)
			)
		)
		(pad "1" smd roundrect
			(at -0.701 0 180)
			(size 0.5 0.6)
			(layers "B.Cu" "B.Mask" "B.Paste")
			(roundrect_rratio 0.25)
			(net 119 "Net-(D710-C)")
			(pinfunction "C")
			(pintype "passive")
		)
		(pad "2" smd roundrect
			(at 0.699 0 180)
			(size 0.5 0.6)
			(layers "B.Cu" "B.Mask" "B.Paste")
			(roundrect_rratio 0.25)
			(net 481 "Net-(D710-A)")
			(pinfunction "A")
			(pintype "passive")
		)
	)
	(footprint "antmicro-footprints:Nexperia_DFN-10_2.5x1mm_P0.5mm"
		(layer "B.Cu")
		(at 126.467962 164.0915 90)
		(property "Reference" "D502"
			(at -1.195 -1.78 90)
			(layer "B.SilkS")
			(effects
				(font
					(size 0.7 0.7)
					(thickness 0.15)
				)
				(justify right bottom mirror)
			)
		)
		(property "Value" "PUSB3F96X_PASS"
			(at -0.016 -1.705 90)
			(layer "B.Fab")
			(effects
				(font
					(size 0.7 0.7)
					(thickness 0.15)
				)
				(justify right bottom mirror)
			)
		)
		(property "Datasheet" "https://mouser.com/datasheet/2/916/PUSB3F96-1600324.pdf"
			(at 0 0 90)
			(layer "B.Fab")
			(hide yes)
			(effects
				(font
					(size 1.27 1.27)
					(thickness 0.15)
				)
			)
		)
		(property "Manufacturer" "Nexperia"
			(at 0 0 90)
			(unlocked yes)
			(layer "B.Fab")
			(hide yes)
			(effects
				(font
					(size 1 1)
					(thickness 0.15)
				)
				(justify mirror)
			)
		)
		(property "MPN" "PUSB3F96X"
			(at 0 0 90)
			(unlocked yes)
			(layer "B.Fab")
			(hide yes)
			(effects
				(font
					(size 1 1)
					(thickness 0.15)
				)
				(justify mirror)
			)
		)
		(property "Author" "Antmicro"
			(at 0 0 90)
			(unlocked yes)
			(layer "B.Fab")
			(hide yes)
			(effects
				(font
					(size 1 1)
					(thickness 0.15)
				)
				(justify mirror)
			)
		)
		(property "License" "Apache-2.0"
			(at 0 0 90)
			(unlocked yes)
			(layer "B.Fab")
			(hide yes)
			(effects
				(font
					(size 1 1)
					(thickness 0.15)
				)
				(justify mirror)
			)
		)
		(sheetname "/NVMe & microSD/")
		(sheetfile "nvme-micro-sd.kicad_sch")
		(attr smd)
		(fp_line
			(start 1.375 -0.4)
			(end 1.375 0.4)
			(stroke
				(width 0.15)
				(type solid)
			)
			(layer "B.SilkS")
		)
		(fp_line
			(start -1.375 0.4)
			(end -1.375 -0.4)
			(stroke
				(width 0.15)
				(type solid)
			)
			(layer "B.SilkS")
		)
		(fp_circle
			(center -1.4 -0.7)
			(end -1.349 -0.7)
			(stroke
				(width 0.15)
				(type solid)
			)
			(fill yes)
			(layer "B.SilkS")
		)
		(fp_rect
			(start -1.4 0.725)
			(end 1.4 -0.725)
			(stroke
				(width 0.05)
				(type solid)
			)
			(fill no)
			(layer "B.CrtYd")
		)
		(fp_line
			(start 1.25 -0.5)
			(end 1.25 0.5)
			(stroke
				(width 0.15)
				(type solid)
			)
			(layer "B.Fab")
		)
		(fp_line
			(start -0.9 -0.5)
			(end 1.25 -0.5)
			(stroke
				(width 0.15)
				(type solid)
			)
			(layer "B.Fab")
		)
		(fp_line
			(start -1.25 -0.15)
			(end -0.9 -0.5)
			(stroke
				(width 0.15)
				(type solid)
			)
			(layer "B.Fab")
		)
		(fp_line
			(start 1.25 0.5)
			(end -1.25 0.5)
			(stroke
				(width 0.15)
				(type solid)
			)
			(layer "B.Fab")
		)
		(fp_line
			(start -1.25 0.5)
			(end -1.25 -0.15)
			(stroke
				(width 0.15)
				(type solid)
			)
			(layer "B.Fab")
		)
		(fp_text user "${REFERENCE}"
			(at -1.367 -3.704 270)
			(layer "B.Fab")
			(effects
				(font
					(size 0.7 0.7)
					(thickness 0.15)
				)
				(justify left bottom mirror)
			)
		)
		(fp_text user "License: Apache-2.0"
			(at -1.367 -6.105 270)
			(layer "B.Fab")
			(effects
				(font
					(size 0.7 0.7)
					(thickness 0.15)
				)
				(justify left bottom mirror)
			)
		)
		(fp_text user "Author: Antmicro"
			(at -1.367 -4.905 270)
			(layer "B.Fab")
			(effects
				(font
					(size 0.7 0.7)
					(thickness 0.15)
				)
				(justify left bottom mirror)
			)
		)
		(pad "1" smd rect
			(at -1 -0.3875 90)
			(size 0.2 0.475)
			(layers "B.Cu" "B.Mask" "B.Paste")
			(net 3 "GND")
			(pinfunction "CH1")
			(pintype "passive")
			(solder_mask_margin 0.05)
		)
		(pad "2" smd rect
			(at -0.5 -0.3875 90)
			(size 0.2 0.475)
			(layers "B.Cu" "B.Mask" "B.Paste")
			(net 7 "/Compute module/SDIO.CLK")
			(pinfunction "CH2")
			(pintype "passive")
			(solder_mask_margin 0.05)
		)
		(pad "3" smd rect
			(at 0 -0.3875 90)
			(size 0.2 0.475)
			(layers "B.Cu" "B.Mask" "B.Paste")
			(net 3 "GND")
			(pinfunction "GND")
			(pintype "passive")
			(solder_mask_margin 0.05)
		)
		(pad "4" smd rect
			(at 0.5 -0.3875 90)
			(size 0.2 0.475)
			(layers "B.Cu" "B.Mask" "B.Paste")
			(net 6 "/Compute module/SDIO.D0")
			(pinfunction "CH3")
			(pintype "passive")
			(solder_mask_margin 0.05)
		)
		(pad "5" smd rect
			(at 1 -0.3875 90)
			(size 0.2 0.475)
			(layers "B.Cu" "B.Mask" "B.Paste")
			(net 5 "/Compute module/SDIO.D1")
			(pinfunction "CH4")
			(pintype "passive")
			(solder_mask_margin 0.05)
		)
		(pad "6" smd rect
			(at 1 0.3875 90)
			(size 0.2 0.475)
			(layers "B.Cu" "B.Mask" "B.Paste")
			(net 5 "/Compute module/SDIO.D1")
			(pinfunction "CH4")
			(pintype "passive")
			(solder_mask_margin 0.05)
		)
		(pad "7" smd rect
			(at 0.5 0.3875 90)
			(size 0.2 0.475)
			(layers "B.Cu" "B.Mask" "B.Paste")
			(net 6 "/Compute module/SDIO.D0")
			(pinfunction "CH3")
			(pintype "passive")
			(solder_mask_margin 0.05)
		)
		(pad "8" smd rect
			(at 0 0.3875 90)
			(size 0.2 0.475)
			(layers "B.Cu" "B.Mask" "B.Paste")
			(net 3 "GND")
			(pinfunction "GND")
			(pintype "passive")
			(solder_mask_margin 0.05)
		)
		(pad "9" smd rect
			(at -0.501 0.3875 90)
			(size 0.2 0.475)
			(layers "B.Cu" "B.Mask" "B.Paste")
			(net 7 "/Compute module/SDIO.CLK")
			(pinfunction "CH2")
			(pintype "passive")
			(solder_mask_margin 0.05)
		)
		(pad "10" smd rect
			(at -1 0.3875 90)
			(size 0.2 0.475)
			(layers "B.Cu" "B.Mask" "B.Paste")
			(net 3 "GND")
			(pinfunction "CH1")
			(pintype "passive")
			(solder_mask_margin 0.05)
		)
	)
	(footprint "antmicro-footprints:DFN3538"
		(layer "B.Cu")
		(at 63.217962 115.1665 -90)
		(property "Reference" "D401"
			(at -1.2865 -3.592038 90)
			(unlocked yes)
			(layer "B.SilkS")
			(effects
				(font
					(size 0.7 0.7)
					(thickness 0.15)
				)
				(justify left bottom mirror)
			)
		)
		(property "Value" "CD-MMBL110S"
			(at 0 -3.5 90)
			(unlocked yes)
			(layer "B.Fab")
			(effects
				(font
					(size 0.7 0.7)
					(thickness 0.15)
				)
				(justify left bottom mirror)
			)
		)
		(property "Datasheet" "https://www.bourns.com/docs/product-datasheets/CD-MMBL110S.pdf"
			(at 0 0 270)
			(layer "B.Fab")
			(hide yes)
			(effects
				(font
					(size 1.27 1.27)
					(thickness 0.15)
				)
			)
		)
		(property "MPN" "CD-MMBL110S"
			(at 0 0 270)
			(unlocked yes)
			(layer "B.Fab")
			(hide yes)
			(effects
				(font
					(size 1 1)
					(thickness 0.15)
				)
				(justify mirror)
			)
		)
		(property "Manufacturer" "Bourns"
			(at 0 0 270)
			(unlocked yes)
			(layer "B.Fab")
			(hide yes)
			(effects
				(font
					(size 1 1)
					(thickness 0.15)
				)
				(justify mirror)
			)
		)
		(property "Author" "Antmicro"
			(at 0 0 270)
			(unlocked yes)
			(layer "B.Fab")
			(hide yes)
			(effects
				(font
					(size 1 1)
					(thickness 0.15)
				)
				(justify mirror)
			)
		)
		(property "License" "Apache-2.0"
			(at 0 0 270)
			(unlocked yes)
			(layer "B.Fab")
			(hide yes)
			(effects
				(font
					(size 1 1)
					(thickness 0.15)
				)
				(justify mirror)
			)
		)
		(sheetname "/Ethernet/")
		(sheetfile "ethernet.kicad_sch")
		(attr smd)
		(fp_line
			(start 0.748 2.452)
			(end 0.748 2.15)
			(stroke
				(width 0.15)
				(type solid)
			)
			(layer "B.SilkS")
		)
		(fp_line
			(start 0.9 2.301)
			(end 0.598 2.301)
			(stroke
				(width 0.15)
				(type solid)
			)
			(layer "B.SilkS")
		)
		(fp_line
			(start -0.902 2.25)
			(end -0.6 2.25)
			(stroke
				(width 0.15)
				(type solid)
			)
			(layer "B.SilkS")
		)
		(fp_line
			(start -0.95 2)
			(end 0.95 2)
			(stroke
				(width 0.15)
				(type solid)
			)
			(layer "B.SilkS")
		)
		(fp_line
			(start 1.6 2)
			(end 1.8 2)
			(stroke
				(width 0.15)
				(type solid)
			)
			(layer "B.SilkS")
		)
		(fp_line
			(start 1.8 2)
			(end 1.8 -2.05)
			(stroke
				(width 0.15)
				(type solid)
			)
			(layer "B.SilkS")
		)
		(fp_line
			(start -1.8 1.5)
			(end -1.8 -2.05)
			(stroke
				(width 0.15)
				(type solid)
			)
			(layer "B.SilkS")
		)
		(fp_line
			(start -1.8 -2.05)
			(end -1.6 -2.05)
			(stroke
				(width 0.15)
				(type solid)
			)
			(layer "B.SilkS")
		)
		(fp_line
			(start -0.95 -2.05)
			(end 0.95 -2.05)
			(stroke
				(width 0.15)
				(type solid)
			)
			(layer "B.SilkS")
		)
		(fp_line
			(start 1.6 -2.05)
			(end 1.8 -2.05)
			(stroke
				(width 0.15)
				(type solid)
			)
			(layer "B.SilkS")
		)
		(fp_rect
			(start -2.1 2.6)
			(end 2.1 -2.6)
			(stroke
				(width 0.05)
				(type solid)
			)
			(fill no)
			(layer "B.CrtYd")
		)
		(fp_line
			(start -1.051 2)
			(end -1.801 1.25)
			(stroke
				(width 0.15)
				(type solid)
			)
			(layer "B.Fab")
		)
		(fp_rect
			(start 1.8 -2.048)
			(end -1.8 2)
			(stroke
				(width 0.15)
				(type solid)
			)
			(fill no)
			(layer "B.Fab")
		)
		(fp_text user "~"
			(at -0.31 -2.7 90)
			(unlocked yes)
			(layer "B.SilkS")
			(effects
				(font
					(size 0.7 0.7)
					(thickness 0.15)
				)
				(justify left bottom mirror)
			)
		)
		(fp_text user "${REFERENCE}"
			(at -2.1 -4.599 90)
			(layer "B.Fab")
			(effects
				(font
					(size 0.7 0.7)
					(thickness 0.15)
				)
				(justify left bottom mirror)
			)
		)
		(fp_text user "License: Apache-2.0"
			(at -2.1 -6.599 90)
			(layer "B.Fab")
			(effects
				(font
					(size 0.7 0.7)
					(thickness 0.15)
				)
				(justify left bottom mirror)
			)
		)
		(fp_text user "Author: Antmicro"
			(at -2.1 -5.599 90)
			(layer "B.Fab")
			(effects
				(font
					(size 0.7 0.7)
					(thickness 0.15)
				)
				(justify left bottom mirror)
			)
		)
		(pad "1" smd roundrect
			(at -1.27 1.85 180)
			(size 1.4 0.48)
			(layers "B.Cu" "B.Mask" "B.Paste")
			(roundrect_rratio 0.25)
			(net 116 "Net-(D401-Pad1)")
			(pinfunction "1")
			(pintype "passive")
		)
		(pad "2" smd roundrect
			(at 1.27 1.85 180)
			(size 1.4 0.48)
			(layers "B.Cu" "B.Mask" "B.Paste")
			(roundrect_rratio 0.25)
			(net 117 "Net-(D401-Pad2)")
			(pinfunction "2")
			(pintype "passive")
		)
		(pad "3" smd roundrect
			(at -1.27 -1.85 180)
			(size 1.4 0.48)
			(layers "B.Cu" "B.Mask" "B.Paste")
			(roundrect_rratio 0.25)
			(net 61 "/Ethernet/PAIR_12")
			(pinfunction "3")
			(pintype "passive")
		)
		(pad "4" smd roundrect
			(at 1.27 -1.85 180)
			(size 1.4 0.48)
			(layers "B.Cu" "B.Mask" "B.Paste")
			(roundrect_rratio 0.25)
			(net 62 "/Ethernet/PAIR_36")
			(pinfunction "4")
			(pintype "passive")
		)
	)
	(footprint "antmicro-footprints:R_0402_1005Metric"
		(layer "B.Cu")
		(at 63.492962 163.1915 180)
		(descr "Resistor SMD 0402")
		(tags "resistor SMD 0402")
		(property "Reference" "R311"
			(at -15.365 0.215 0)
			(layer "B.SilkS")
			(effects
				(font
					(size 0.7 0.7)
					(thickness 0.15)
				)
				(justify left bottom mirror)
			)
		)
		(property "Value" "R_10k_0402"
			(at -1.011843 -1.772047 0)
			(layer "B.Fab")
			(effects
				(font
					(size 0.7 0.7)
					(thickness 0.15)
				)
				(justify left bottom mirror)
			)
		)
		(property "Datasheet" "https://www.bourns.com/docs/product-datasheets/cr.pdf"
			(at 0 0 180)
			(layer "B.Fab")
			(hide yes)
			(effects
				(font
					(size 1.27 1.27)
					(thickness 0.15)
				)
			)
		)
		(property "Manufacturer" "Bourns"
			(at 0 0 180)
			(unlocked yes)
			(layer "B.Fab")
			(hide yes)
			(effects
				(font
					(size 1 1)
					(thickness 0.15)
				)
				(justify mirror)
			)
		)
		(property "MPN" "CR0402-FX-1002GLF"
			(at 0 0 180)
			(unlocked yes)
			(layer "B.Fab")
			(hide yes)
			(effects
				(font
					(size 1 1)
					(thickness 0.15)
				)
				(justify mirror)
			)
		)
		(property "Val" "10k"
			(at 0 0 180)
			(unlocked yes)
			(layer "B.Fab")
			(hide yes)
			(effects
				(font
					(size 1 1)
					(thickness 0.15)
				)
				(justify mirror)
			)
		)
		(property "License" "Apache-2.0"
			(at 0 0 180)
			(unlocked yes)
			(layer "B.Fab")
			(hide yes)
			(effects
				(font
					(size 1 1)
					(thickness 0.15)
				)
				(justify mirror)
			)
		)
		(property "Author" "Antmicro"
			(at 0 0 180)
			(unlocked yes)
			(layer "B.Fab")
			(hide yes)
			(effects
				(font
					(size 1 1)
					(thickness 0.15)
				)
				(justify mirror)
			)
		)
		(property "Tolerance" "1%"
			(at 0 0 180)
			(unlocked yes)
			(layer "B.Fab")
			(hide yes)
			(effects
				(font
					(size 1 1)
					(thickness 0.15)
				)
				(justify mirror)
			)
		)
		(sheetname "/Supply/")
		(sheetfile "supply.kicad_sch")
		(attr smd)
		(fp_rect
			(start -0.925 0.47)
			(end 0.925 -0.47)
			(stroke
				(width 0.05)
				(type default)
			)
			(fill no)
			(layer "B.CrtYd")
		)
		(fp_rect
			(start -0.5 0.25)
			(end 0.5 -0.25)
			(stroke
				(width 0.15)
				(type solid)
			)
			(fill no)
			(layer "B.Fab")
		)
		(fp_text user "${REFERENCE}"
			(at -0.95 -3.168 0)
			(layer "B.Fab")
			(effects
				(font
					(size 0.7 0.7)
					(thickness 0.15)
				)
				(justify left bottom mirror)
			)
		)
		(fp_text user "License: Apache-2.0"
			(at -0.95 -5.169 0)
			(layer "B.Fab")
			(effects
				(font
					(size 0.7 0.7)
					(thickness 0.15)
				)
				(justify left bottom mirror)
			)
		)
		(fp_text user "Author: Antmicro"
			(at -0.95 -4.169 0)
			(layer "B.Fab")
			(effects
				(font
					(size 0.7 0.7)
					(thickness 0.15)
				)
				(justify left bottom mirror)
			)
		)
		(pad "1" smd roundrect
			(at -0.48 0 180)
			(size 0.59 0.64)
			(layers "B.Cu" "B.Mask" "B.Paste")
			(roundrect_rratio 0.25)
			(net 350 "/Supply/EN_3V3")
			(pintype "passive")
		)
		(pad "2" smd roundrect
			(at 0.48 0 180)
			(size 0.59 0.64)
			(layers "B.Cu" "B.Mask" "B.Paste")
			(roundrect_rratio 0.25)
			(net 43 "VCC")
			(pintype "passive")
		)
	)
)
